FILE_TYPE = MULTI_PHYS_TABLE;

PART 'ME_DUMMY_SYMBOL'

{========================================================================================}
:VALUE                            | PART_TYPE | MATERIAL | PART_NUMBER           = STANDARD | LIFECYCLE | PART_NUMBER           | JEDEC_TYPE                       | DESCRIPTION                                       | MANUFTR | MANUF_PN      | RD_CMPLS_LVL | CMPLS_LVL | CLASS        | DIP_SMD | FROM_PJ        | DATA                      | FP_ECN                                      | EE_CHECK_LIST | PSL | PREFERENCE | CREATOR | CREATEDAY  | STATUS | ESD_CDM | ESD_HBM | ESD_MM | MSD | PIN_LENGTH_LONG_PIN | PIN_LENGTH_SHORT_PIN ;
{========================================================================================}
 'xlga3647_h3760x_left_p0'        | 'Mech'    | 'EMPTY'  | 'DUMMY37'(!)          = ''       | ''        | 'DUMMY37'             |'XLGA3647_H3760X_LEFT_P0'| 'xlga3647_h3760x_left_p0'                         | ''      | ''            | ''           | ''        | 'MECHANICAL' | ''      | ''             | ''                        | ''                                          | ''            | ''  | ''         | ''      | '20170104' | ''     | ''      | ''      | ''     | ''  | ''                  | ''                  
 'xlga3647_h3760x_right_p0'       | 'Mech'    | 'EMPTY'  | 'DUMMY38'(!)          = ''       | ''        | 'DUMMY38'             |'XLGA3647_H3760X_RIGHT_P0'| 'xlga3647_h3760x_right_p0'                        | ''      | ''            | ''           | ''        | 'MECHANICAL' | ''      | ''             | ''                        | ''                                          | ''            | ''  | ''         | ''      | '20170104' | ''     | ''      | ''      | ''     | ''  | ''                  | ''                  
 'CBS_3X558-8'                    | 'Mech'    | 'EMPTY'  | 'DUMMY47'(!)          = ''       | ''        | 'DUMMY47'             |'CBS_3X558-8'| 'CBS_3MMX558-8MM'                                 | ''      | ''            | ''           | ''        | 'MECHANICAL' | ''      | ''             | ''                        | ''                                          | ''            | ''  | ''         | ''      | '20170731' | ''     | ''      | ''      | ''     | ''  | ''                  | ''                  
 'PICKUP_SMDC20'                  | 'Mech'    | 'EMPTY'  | 'DUMMY48'(!)          = ''       | ''        | 'DUMMY48'             |'PICKUP_SMDC20'| 'PICKUP_SMDC20'                                   | ''      | ''            | ''           | ''        | 'MECHANICAL' | ''      | ''             | ''                        | ''                                          | ''            | ''  | ''         | ''      | '20170731' | ''     | ''      | ''      | ''     | ''  | ''                  | ''                  
 'PICKUP_SMDC10'                  | 'Mech'    | 'EMPTY'  | 'DUMMY49'(!)          = ''       | ''        | 'DUMMY49'             |'PICKUP_SMDC10'| 'PICKUP_SMDC10'                                   | ''      | ''            | ''           | ''        | 'MECHANICAL' | ''      | ''             | ''                        | ''                                          | ''            | ''  | ''         | ''      | '20170731' | ''     | ''      | ''      | ''     | ''  | ''                  | ''                  
 'MACLABEL_17X12'                 | 'Mech'    | 'EMPTY'  | 'DUMMY51'(!)          = ''       | ''        | 'DUMMY51'             |'MACLABEL_17X12'| 'MACLABEL_17X12'                                  | ''      | ''            | ''           | ''        | 'MECHANICAL' | ''      | ''             | ''                        | ''                                          | ''            | ''  | ''         | ''      | '20170920' | ''     | ''      | ''      | ''     | ''  | ''                  | ''                  
 'MSFTLABEL_27X6'                 | 'Mech'    | 'EMPTY'  | 'DUMMY52'(!)          = ''       | ''        | 'DUMMY52'             |'MSFTLABEL_27X6'| 'MSFTLABEL_27X6'                                  | ''      | ''            | ''           | ''        | 'MECHANICAL' | ''      | ''             | ''                        | ''                                          | ''            | ''  | ''         | ''      | '20170922' | ''     | ''      | ''      | ''     | ''  | ''                  | ''                  
 'xlga4189_j73622_left_p4'        | 'Mech'    | 'EMPTY'  | 'DUMMY53'(!)          = ''       | ''        | 'DUMMY53'             |'XLGA4189_J73622_LEFT_P4'| 'xlga4189_j73622_left_p4'                         | ''      | ''            | ''           | ''        | 'MECHANICAL' | ''      | ''             | ''                        | ''                                          | ''            | ''  | ''         | ''      | '20180116' | ''     | ''      | ''      | ''     | ''  | ''                  | ''                  
 'xlga4189_j73622_right_p4'       | 'Mech'    | 'EMPTY'  | 'DUMMY54'(!)          = ''       | ''        | 'DUMMY54'             |'XLGA4189_J73622_RIGHT_P4'| 'xlga4189_j73622_right_p4'                        | ''      | ''            | ''           | ''        | 'MECHANICAL' | ''      | ''             | ''                        | ''                                          | ''            | ''  | ''         | ''      | '20180116' | ''     | ''      | ''      | ''     | ''  | ''                  | ''                  
 'Alibaba Logo_16X14'             | 'Mech'    | 'EMPTY'  | 'DUMMY55'(!)          = ''       | ''        | 'DUMMY55'             |'ALIBABA_LOGO_16X14'| 'Alibaba Logo_16X14'                              | ''      | ''            | ''           | ''        | 'MECHANICAL' | ''      | ''             | ''                        | ''                                          | ''            | ''  | ''         | ''      | '20180201' | ''     | ''      | ''      | ''     | ''  | ''                  | ''                  
 'ELECTRICAL_HAZARD_LOGO'         | 'Mech'    | 'EMPTY'  | 'DUMMY56'(!)          = ''       | ''        | 'DUMMY56'             |'ELECTRICAL_HAZARD_LOGO'| 'ELECTRICAL_HAZARD_LOGO'                          | ''      | ''            | ''           | ''        | 'MECHANICAL' | ''      | ''             | ''                        | ''                                          | ''            | ''  | ''         | ''      | '20180323' | ''     | ''      | ''      | ''     | ''  | ''                  | ''                  
 'ELECTRICAL_HAZARD_LOGO_6-6X5-7' | 'Mech'    | 'EMPTY'  | 'DUMMY57'(!)          = ''       | ''        | 'DUMMY57'             |'ELECTRICAL_HAZARD_LOGO_6-6X5-7'| 'ELECTRICAL_HAZARD_LOGO_6-6X5-7'                  | ''      | ''            | ''           | ''        | 'MECHANICAL' | ''      | ''             | ''                        | ''                                          | ''            | ''  | ''         | ''      | '20180409' | ''     | ''      | ''      | ''     | ''  | ''                  | ''                  
 'QUANTA_LOGO_2X7-6'              | 'Mech'    | 'EMPTY'  | 'DUMMY58'(!)          = ''       | ''        | 'DUMMY58'             |'QUANTA_LOGO_2X7-6'| 'QUANTA_LOGO_2X7-6'                               | ''      | ''            | ''           | ''        | 'MECHANICAL' | ''      | ''             | ''                        | ''                                          | ''            | ''  | ''         | ''      | '20180424' | ''     | ''      | ''      | ''     | ''  | ''                  | ''                  
 'NOKIA_LOGO_12-7X2-1'            | 'Mech'    | 'EMPTY'  | 'DUMMY59'(!)          = ''       | ''        | 'DUMMY59'             |'NOKIA_LOGO_12-7X2-1'| 'NOKIA_LOGO_12-7X2-1'                             | ''      | ''            | ''           | ''        | 'MECHANICAL' | ''      | ''             | ''                        | ''                                          | ''            | ''  | ''         | ''      | '20180629' | ''     | ''      | ''      | ''     | ''  | ''                  | ''                  
 'NOKIA_LOGO_20X3-3'              | 'Mech'    | 'EMPTY'  | 'DUMMY60'(!)          = ''       | ''        | 'DUMMY60'             |'NOKIA_LOGO_20X3-3'| 'NOKIA_LOGO_20X3-3'                               | ''      | ''            | ''           | ''        | 'MECHANICAL' | ''      | ''             | ''                        | ''                                          | ''            | ''  | ''         | ''      | '20180629' | ''     | ''      | ''      | ''     | ''  | ''                  | ''                  
 'xlga4189_j73622_left_p5'        | 'Mech'    | 'EMPTY'  | 'DUMMY61'(!)          = ''       | ''        | 'DUMMY61'             |'XLGA4189_J73622_LEFT_P5'| 'xlga4189_j73622_left_p5(SOCKET4189S_82X62XA)'    | ''      | ''            | ''           | ''        | 'MECHANICAL' | ''      | ''             | ''                        | ''                                          | ''            | ''  | ''         | ''      | '20190306' | ''     | ''      | ''      | ''     | ''  | ''                  | ''                  
 'xlga4189_j73622_right_p5'       | 'Mech'    | 'EMPTY'  | 'DUMMY62'(!)          = ''       | ''        | 'DUMMY62'             |'XLGA4189_J73622_RIGHT_P5'| 'xlga4189_j73622_right_p5(SOCKET4189S_82X62XA)'   | ''      | ''            | ''           | ''        | 'MECHANICAL' | ''      | ''             | ''                        | ''                                          | ''            | ''  | ''         | ''      | '20190306' | ''     | ''      | ''      | ''     | ''  | ''                  | ''                  
 'PICKUP_SMDC30'                  | 'Mech'    | 'EMPTY'  | 'DUMMY63'(!)          = ''       | ''        | 'DUMMY63'             |'PICKUP_SMDC30'| 'PICKUP_SMDC30'                                   | ''      | ''            | ''           | ''        | 'MECHANICAL' | ''      | ''             | ''                        | ''                                          | ''            | ''  | ''         | ''      | '20190717' | ''     | ''      | ''      | ''     | ''  | ''                  | ''                  
 'TENCENT_LOGO_12-05X2-25'        | 'Mech'    | 'EMPTY'  | 'DUMMY65'(!)          = ''       | ''        | 'DUMMY65'             |'TENCENT_LOGO_12-05X2-25'| 'TENCENT_LOGO_12-05X2-25'                         | ''      | ''            | ''           | ''        | 'MECHANICAL' | ''      | ''             | ''                        | ''                                          | ''            | ''  | ''         | ''      | '20191007' | ''     | ''      | ''      | ''     | ''  | ''                  | ''                  
 'TENCENT_LOGO_38-16X7-23'        | 'Mech'    | 'EMPTY'  | 'DUMMY66'(!)          = ''       | ''        | 'DUMMY66'             |'TENCENT_LOGO_38-16X7-23'| 'TENCENT_LOGO_38-16X7-23'                         | ''      | ''            | ''           | ''        | 'MECHANICAL' | ''      | ''             | ''                        | ''                                          | ''            | ''  | ''         | ''      | '20191015' | ''     | ''      | ''      | ''     | ''  | ''                  | ''                  
 'MACLABEL_32-75X7-35'            | 'Mech'    | 'EMPTY'  | 'DUMMY67'(!)          = ''       | ''        | 'DUMMY67'             |'MACLABEL_32-75X7-35'| 'MACLABEL_32-75X7-35'                             | ''      | ''            | ''           | ''        | 'MECHANICAL' | ''      | ''             | ''                        | ''                                          | ''            | ''  | ''         | ''      | '20200504' | ''     | ''      | ''      | ''     | ''  | ''                  | ''                  
 'BMCLABEL_12X15'                 | 'Mech'    | 'EMPTY'  | 'DUMMY68'(!)          = ''       | ''        | 'DUMMY68'             |'BMCLABEL_12X15'| 'BMCLABEL_12X15'                                  | ''      | ''            | ''           | ''        | 'MECHANICAL' | ''      | ''             | ''                        | ''                                          | ''            | ''  | ''         | ''      | '20200504' | ''     | ''      | ''      | ''     | ''  | ''                  | ''                  
 'SNLABEL_7X7'                    | 'Mech'    | 'EMPTY'  | 'DUMMY69'(!)          = ''       | ''        | 'DUMMY69'             |'SNLABEL_7X7'| 'SNLABEL_7X7'                                     | ''      | ''            | ''           | ''        | 'MECHANICAL' | ''      | ''             | ''                        | ''                                          | ''            | ''  | ''         | ''      | '20200526' | ''     | ''      | ''      | ''     | ''  | ''                  | ''                  
 'PNLABEL_23-5X5'                 | 'Mech'    | 'EMPTY'  | 'DUMMY70'(!)          = ''       | ''        | 'DUMMY70'             |'PNLABEL_23-5X5'| 'PNLABEL_23-5X5'                                  | ''      | ''            | ''           | ''        | 'MECHANICAL' | ''      | ''             | ''                        | ''                                          | ''            | ''  | ''         | ''      | '20200526' | ''     | ''      | ''      | ''     | ''  | ''                  | ''                  
 'REWORKLABEL_39-5X6-5'           | 'Mech'    | 'EMPTY'  | 'DUMMY71'(!)          = ''       | ''        | 'DUMMY71'             |'REWORKLABEL_39-5X6-5'| 'REWORKLABEL_39-5X6-5'                            | ''      | ''            | ''           | ''        | 'MECHANICAL' | ''      | ''             | ''                        | ''                                          | ''            | ''  | ''         | ''      | '20200826' | ''     | ''      | ''      | ''     | ''  | ''                  | ''                  
 'QUANTA_LOGO_7X26'               | 'Mech'    | 'EMPTY'  | 'DUMMY1'(!)           = ''       | ''        | 'DUMMY1'              |'QUANTA_LOGO_7X26'| 'QUANTA_LOGO_7X26'                                | ''      | ''            | ''           | ''        | 'MECHANICAL' | ''      | ''             | ''                        | ''                                          | ''            | ''  | ''         | ''      | '20141104' | ''     | ''      | ''      | ''     | ''  | ''                  | ''                  
 'WEEE'                           | 'Mech'    | 'EMPTY'  | 'DUMMY2'(!)           = ''       | ''        | 'DUMMY2'              |'WEEE'| 'WEEE'                                            | ''      | ''            | ''           | ''        | 'MECHANICAL' | ''      | ''             | ''                        | ''                                          | ''            | ''  | ''         | ''      | '20141104' | ''     | ''      | ''      | ''     | ''  | ''                  | ''                  
 'BIOS-BMCLABEL_10-5X10-5'        | 'Mech'    | 'EMPTY'  | 'DUMMY5'(!)           = ''       | ''        | 'DUMMY5'              |'BIOS-BMCLABEL_10-5X10-5'| 'BIOS-BMCLABEL_10-5X10-5'                         | ''      | ''            | ''           | ''        | 'MECHANICAL' | ''      | ''             | ''                        | ''                                          | ''            | ''  | ''         | ''      | '20141104' | ''     | ''      | ''      | ''     | ''  | ''                  | ''                  
 'Legacy BIOS Label'              | 'Mech'    | 'EMPTY'  | 'DUMMY27_AP0SERVER05'(!) = ''       | ''        | 'DUMMY27_AP0SERVER05' |'BIOS-BMCLABEL_10-5X10-5'| 'BIOS LICENCE AMI SERVER BIOS LABEL'              | ''      | ''            | ''           | ''        | 'MECHANICAL' | ''      | ''             | ''                        | ''                                          | ''            | ''  | ''         | ''      | '20160105' | ''     | ''      | ''      | ''     | ''  | ''                  | ''                  
 'EFI BIOS Label'                 | 'Mech'    | 'EMPTY'  | 'DUMMY28_HCLU2002010'(!) = ''       | ''        | 'DUMMY28_HCLU2002010' |'BIOS-BMCLABEL_10-5X10-5'| 'EFI BIOS LABEL LU2(HCLU2002,REV3A)'              | ''      | ''            | ''           | ''        | 'MECHANICAL' | ''      | ''             | ''                        | ''                                          | ''            | ''  | ''         | ''      | '20160105' | ''     | ''      | ''      | ''     | ''  | ''                  | ''                  
 'xlga4189_j73622_left_p4'        | 'Mech'    | 'MECH'   | 'DGA^0000070'(!)      = ''       | ''        | 'DGA^0000070'         |'XLGA4189_J73622_LEFT_P4'| 'SOCKET 2097P P4-LSA LGA(P0.8585,H7.75)'          | 'TYC'   | '1-2324271-4' | 'EP(V1)'     | 'EP(V1)'  | 'MECHANICAL' | ''      | 'S6YQ-COOPER'  | ''                        | ''                                          | ''            | ''  | ''         | ''      | '20210917' | ''     | ''      | ''      | ''     | ''  | ''                  | ''                  
 'xlga4189_j73622_left_p4'        | 'Mech'    | 'EMPTY'  | 'DGA^0000070'(!)      = ''       | ''        | 'DGA^0000070'         |'XLGA4189_J73622_LEFT_P4'| 'SOCKET 2097P P4-LSA LGA(P0.8585,H7.75)'          | 'TYC'   | '1-2324271-4' | 'EP(V1)'     | 'EP(V1)'  | 'MECHANICAL' | ''      | 'S6YQ-COOPER'  | ''                        | ''                                          | ''            | ''  | ''         | ''      | '20210917' | ''     | ''      | ''      | ''     | ''  | ''                  | ''                  
 'xlga4189_j73622_right_p4'       | 'Mech'    | 'MECH'   | 'DGA^0000069'(!)      = ''       | ''        | 'DGA^0000069'         |'XLGA4189_J73622_RIGHT_P4'| 'SOCKET 2092P P4-RSA LGA(P0.8585,H7.75)'          | 'TYC'   | '1-2324271-3' | 'EP(V1)'     | 'EP(V1)'  | 'MECHANICAL' | ''      | 'S6YQ-COOPER'  | ''                        | ''                                          | ''            | ''  | ''         | ''      | '20210917' | ''     | ''      | ''      | ''     | ''  | ''                  | ''                  
 'xlga4189_j73622_right_p4'       | 'Mech'    | 'EMPTY'  | 'DGA^0000069'(!)      = ''       | ''        | 'DGA^0000069'         |'XLGA4189_J73622_RIGHT_P4'| 'SOCKET 2092P P4-RSA LGA(P0.8585,H7.75)'          | 'TYC'   | '1-2324271-3' | 'EP(V1)'     | 'EP(V1)'  | 'MECHANICAL' | ''      | 'S6YQ-COOPER'  | ''                        | ''                                          | ''            | ''  | ''         | ''      | '20210917' | ''     | ''      | ''      | ''     | ''  | ''                  | ''                  
 'PB-E1_SMALL'                    | 'Mech'    | 'EMPTY'  | 'DUMMY3'(!)           = ''       | ''        | 'DUMMY3'              |'PB-E1_SMALL'| 'PB-E1_SMALL'                                     | ''      | ''            | ''           | ''        | 'MECHANICAL' | ''      | ''             | ''                        | ''                                          | ''            | ''  | ''         | ''      | '20210923' | ''     | ''      | ''      | ''     | ''  | ''                  | ''                  
 'PCBA_LABEL_15X5'                | 'Mech'    | 'EMPTY'  | 'DUMMY4'(!)           = ''       | ''        | 'DUMMY4'              |'PNLABEL_15X5'| 'PCBA_LABEL_15X5'                                 | ''      | ''            | ''           | ''        | 'MECHANICAL' | ''      | ''             | ''                        | ''                                          | ''            | ''  | ''         | ''      | '20210923' | ''     | ''      | ''      | ''     | ''  | ''                  | ''                  
 'BARCODE'                        | 'Mech'    | 'EMPTY'  | 'DUMMY6'(!)           = ''       | ''        | 'DUMMY6'              |'BARCODE'| 'SERIEL_LABEL'                                    | ''      | ''            | ''           | ''        | 'MECHANICAL' | ''      | ''             | ''                        | ''                                          | ''            | ''  | ''         | ''      | '20210923' | ''     | ''      | ''      | ''     | ''  | ''                  | ''                  
 'PCB_VENDOR_LOGO_15X8'           | 'Mech'    | 'EMPTY'  | 'DUMMY7'(!)           = ''       | ''        | 'DUMMY7'              |'PCB_VENDOR_LOGO_15X8'| 'PCB_VENDOR_LOGO_15X8'                            | ''      | ''            | ''           | ''        | 'MECHANICAL' | ''      | ''             | ''                        | ''                                          | ''            | ''  | ''         | ''      | '20210923' | ''     | ''      | ''      | ''     | ''  | ''                  | ''                  
 'QCT_LOGO_12X12'                 | 'Mech'    | 'EMPTY'  | 'DUMMY13'(!)          = ''       | ''        | 'DUMMY13'             |'QCT_LOGO_12X12'| 'QCT_LOGO_12X12'                                  | ''      | ''            | ''           | ''        | 'MECHANICAL' | ''      | ''             | ''                        | ''                                          | ''            | ''  | ''         | ''      | '20210923' | ''     | ''      | ''      | ''     | ''  | ''                  | ''                  
 'BARCODE_25X6'                   | 'Mech'    | 'EMPTY'  | 'DUMMY14'(!)          = ''       | ''        | 'DUMMY14'             |'BARCODE_25X6'| 'BARCODE_25X6'                                    | ''      | ''            | ''           | ''        | 'MECHANICAL' | ''      | 'S2SP-CHRIS'   | ''                        | ''                                          | ''            | ''  | ''         | ''      | '20210923' | ''     | ''      | ''      | ''     | ''  | ''                  | ''                  
 'BARCODE_20X6'                   | 'Mech'    | 'EMPTY'  | 'DUMMY15'(!)          = ''       | ''        | 'DUMMY15'             |'BARCODE_20X6'| 'BARCODE_20X6'                                    | ''      | ''            | ''           | ''        | 'MECHANICAL' | ''      | 'UH3-JACK'     | ''                        | ''                                          | ''            | ''  | ''         | ''      | '20210923' | ''     | ''      | ''      | ''     | ''  | ''                  | ''                  
 'CE_LOGO_5.8X5.08'               | 'Mech'    | 'EMPTY'  | 'DUMMY18'(!)          = ''       | ''        | 'DUMMY18'             |'CE'| 'CE LOGO_5.842X5.08'                              | ''      | ''            | ''           | ''        | 'MECHANICAL' | ''      | 'T6MG-RAYMOND' | 'Safety EMC logo.xlsx'    | ''                                          | ''            | ''  | ''         | ''      | '20210923' | ''     | ''      | ''      | ''     | ''  | ''                  | ''                  
 'CE_LOGO_11.5X10.2'              | 'Mech'    | 'EMPTY'  | 'DUMMY19'(!)          = ''       | ''        | 'DUMMY19'             |'CE_Q'| 'CE_LOGO_11.481X10.185'                           | ''      | ''            | ''           | ''        | 'MECHANICAL' | ''      | 'T6MG-RAYMOND' | 'Safety EMC logo.xlsx'    | ''                                          | ''            | ''  | ''         | ''      | '20210923' | ''     | ''      | ''      | ''     | ''  | ''                  | ''                  
 'CE_LOGO_4.8X4'                  | 'Mech'    | 'EMPTY'  | 'DUMMY20'(!)          = ''       | ''        | 'DUMMY20'             |'CE_5X4'| 'CE_LOGO_4.826X4.064'                             | ''      | ''            | ''           | ''        | 'MECHANICAL' | ''      | 'T6MG-RAYMOND' | 'Safety EMC logo.xlsx'    | ''                                          | ''            | ''  | ''         | ''      | '20210923' | ''     | ''      | ''      | ''     | ''  | ''                  | ''                  
 'RCM_LOGO'                       | 'Mech'    | 'EMPTY'  | 'DUMMY21'(!)          = ''       | ''        | 'DUMMY21'             |'RCM'| 'RCM_LOGO'                                        | ''      | ''            | ''           | ''        | 'MECHANICAL' | ''      | 'T6MG-RAYMOND' | 'Safety EMC logo.xlsx'    | ''                                          | ''            | ''  | ''         | ''      | '20210923' | ''     | ''      | ''      | ''     | ''  | ''                  | ''                  
 'KCCA_LOGO'                      | 'Mech'    | 'EMPTY'  | 'DUMMY22'(!)          = ''       | ''        | 'DUMMY22'             |'KCCA'| 'KCCA_LOGO'                                       | ''      | ''            | ''           | ''        | 'MECHANICAL' | ''      | 'T6MG-RAYMOND' | 'Safety EMC logo.xlsx'    | ''                                          | ''            | ''  | ''         | ''      | '20210923' | ''     | ''      | ''      | ''     | ''  | ''                  | ''                  
 'SNLABEL_20X6'                   | 'Mech'    | 'EMPTY'  | 'DUMMY25'(!)          = ''       | ''        | 'DUMMY25'             |'SNLABEL_20X6'| 'SNLABEL_20X6'                                    | ''      | ''            | ''           | ''        | 'MECHANICAL' | ''      | 'JSA-DENNY'    | ''                        | ''                                          | ''            | ''  | ''         | ''      | '20210923' | ''     | ''      | ''      | ''     | ''  | ''                  | ''                  
 'SNLABEL_31-75X6-35'             | 'Mech'    | 'EMPTY'  | 'DUMMY26'(!)          = ''       | ''        | 'DUMMY26'             |'SNLABEL_31-75X6-35'| 'SNLABEL_31-75X6-35_SEL'                          | ''      | ''            | ''           | ''        | 'MECHANICAL' | ''      | 'T2H-GAVEN'    | 'SNLABEL_31-75X6-35.pdf'  | 'SNLABEL_31-75X6-35.pdf'                    | ''            | ''  | ''         | ''      | '20210923' | ''     | ''      | ''      | ''     | ''  | ''                  | ''                  
 'GPNLABEL_31-75X6-35'            | 'Mech'    | 'EMPTY'  | 'DUMMY29'(!)          = ''       | ''        | 'DUMMY29'             |'GPNLABEL_31-75X6-35'| 'GPNLABEL_31-75X6-35_SEL'                         | ''      | ''            | ''           | ''        | 'MECHANICAL' | ''      | 'T2H-WADE'     | 'GPNLABEL_31-75X6-35.pdf' | ''                                          | ''            | ''  | ''         | ''      | '20210923' | ''     | ''      | ''      | ''     | ''  | ''                  | ''                  
 'UL_LOGO_E142692_7.3X4.4'        | 'Mech'    | 'EMPTY'  | 'DUMMY30'(!)          = ''       | ''        | 'DUMMY30'             |'UL_E142692'| 'UL_LOGO_E142692_7.3X4.4(UL File number E142692)' | ''      | ''            | ''           | ''        | 'MECHANICAL' | ''      | 'F20-OWEN'     | ''                        | 'UL_LOGO_E142692_7.3X4.4.pdf'               | ''            | ''  | ''         | ''      | '20210923' | ''     | ''      | ''      | ''     | ''  | ''                  | ''                  
 'FCC_LOGO'                       | 'Mech'    | 'EMPTY'  | 'DUMMY31'(!)          = ''       | ''        | 'DUMMY31'             |'FCC'| 'FCC_LOGO_11.2X7.9'                               | ''      | ''            | ''           | ''        | 'MECHANICAL' | ''      | ''             | ''                        | ''                                          | ''            | ''  | ''         | ''      | '20210923' | ''     | ''      | ''      | ''     | ''  | ''                  | ''                  
 'BARCODE_40X6'                   | 'Mech'    | 'EMPTY'  | 'DUMMY32'(!)          = ''       | ''        | 'DUMMY32'             |'BARCODE_40X6'| 'BARCODE_40X6'                                    | ''      | ''            | ''           | ''        | 'MECHANICAL' | ''      | 'S5D-THOMAS'   | ''                        | ''                                          | ''            | ''  | ''         | ''      | '20210923' | ''     | ''      | ''      | ''     | ''  | ''                  | ''                  
 'BARCODE_15X5'                   | 'Mech'    | 'EMPTY'  | 'DUMMY34'(!)          = ''       | ''        | 'DUMMY34'             |'BARCODE_15X5'| 'BARCODE_15X5'                                    | ''      | ''            | ''           | ''        | 'MECHANICAL' | ''      | 'A5W-MARCUS'   | ''                        | 'BARCODE_15X5.msg'                          | ''            | ''  | ''         | ''      | '20210923' | ''     | ''      | ''      | ''     | ''  | ''                  | ''                  
 'SNLABEL_50-8X6-35'              | 'Mech'    | 'EMPTY'  | 'DUMMY35'(!)          = ''       | ''        | 'DUMMY35'             |'SNLABEL_50-8X6-35'| 'SNLABEL_50-8X6-35'                               | ''      | ''            | ''           | ''        | 'MECHANICAL' | ''      | 'STUDY-CANDY'  | ''                        | 'SNLABEL_50-8X6-35 & SNLABEL_15X5.msg'      | ''            | ''  | ''         | ''      | '20210923' | ''     | ''      | ''      | ''     | ''  | ''                  | ''                  
 'SNLABEL_15X5'                   | 'Mech'    | 'EMPTY'  | 'DUMMY36'(!)          = ''       | ''        | 'DUMMY36'             |'SNLABEL_15X5'| 'SNLABEL_15X5'                                    | ''      | ''            | ''           | ''        | 'MECHANICAL' | ''      | 'STUDY-CANDY'  | ''                        | 'SNLABEL_50-8X6-35 & SNLABEL_15X5.msg'      | ''            | ''  | ''         | ''      | '20210923' | ''     | ''      | ''      | ''     | ''  | ''                  | ''                  
 'MICROSOFT_LOGO_7X33'            | 'Mech'    | 'EMPTY'  | 'DUMMY40'(!)          = ''       | ''        | 'DUMMY40'             |'MICROSOFT_LOGO_7X33'| 'MICROSOFT_LOGO_7X33'                             | ''      | ''            | ''           | ''        | 'MECHANICAL' | ''      | 'T6U-JH'       | ''                        | ''                                          | ''            | ''  | ''         | ''      | '20210923' | ''     | ''      | ''      | ''     | ''  | ''                  | ''                  
 'PNLABEL_19-5X8'                 | 'Mech'    | 'EMPTY'  | 'DUMMY41'(!)          = ''       | ''        | 'DUMMY41'             |'PNLABEL_19-5X8'| 'PNLABEL_19-5X8'                                  | ''      | ''            | ''           | ''        | 'MECHANICAL' | ''      | 'F0A-BERNIE'   | ''                        | ''                                          | ''            | ''  | ''         | ''      | '20210923' | ''     | ''      | ''      | ''     | ''  | ''                  | ''                  
 'BARCODE_49-5X8-35'              | 'Mech'    | 'EMPTY'  | 'DUMMY42'(!)          = ''       | ''        | 'DUMMY42'             |'BARCODE_49-5X8-35'| 'BARCODE_49-5X8-35'                               | ''      | ''            | ''           | ''        | 'MECHANICAL' | ''      | 'F0A-BERNIE'   | ''                        | ''                                          | ''            | ''  | ''         | ''      | '20210923' | ''     | ''      | ''      | ''     | ''  | ''                  | ''                  
 'BARCODE_27X8'                   | 'Mech'    | 'EMPTY'  | 'DUMMY43'(!)          = ''       | ''        | 'DUMMY43'             |'BARCODE_27X8'| 'BARCODE_27X8'                                    | ''      | ''            | ''           | ''        | 'MECHANICAL' | ''      | 'F0A-BERNIE'   | ''                        | ''                                          | ''            | ''  | ''         | ''      | '20210923' | ''     | ''      | ''      | ''     | ''  | ''                  | ''                  
 'SNLABEL_47-5X6-35'              | 'Mech'    | 'EMPTY'  | 'DUMMY44'(!)          = ''       | ''        | 'DUMMY44'             |'SNLABEL_47-5X6-35'| 'SNLABEL_47-5X6-35'                               | ''      | ''            | ''           | ''        | 'MECHANICAL' | ''      | ''             | ''                        | 'FW DFx of the PCB and PCBA Discussion.msg' | ''            | ''  | ''         | ''      | '20210923' | ''     | ''      | ''      | ''     | ''  | ''                  | ''                  
 'SNLABEL_17-5X6'                 | 'Mech'    | 'EMPTY'  | 'DUMMY45'(!)          = ''       | ''        | 'DUMMY45'             |'SNLABEL_17-5X6'| 'SNLABEL_17-5X6'                                  | ''      | ''            | ''           | ''        | 'MECHANICAL' | ''      | ''             | ''                        | 'FW DFx of the PCB and PCBA Discussion.msg' | ''            | ''  | ''         | ''      | '20210923' | ''     | ''      | ''      | ''     | ''  | ''                  | ''                  
 'SNLABEL_27X6'                   | 'Mech'    | 'EMPTY'  | 'DUMMY46'(!)          = ''       | ''        | 'DUMMY46'             |'SNLABEL_27X6'| 'SNLABEL_27X6'                                    | ''      | ''            | ''           | ''        | 'MECHANICAL' | ''      | ''             | ''                        | 'FW DFx of the PCB and PCBA Discussion.msg' | ''            | ''  | ''         | ''      | '20210923' | ''     | ''      | ''      | ''     | ''  | ''                  | ''                  
 'SNLABEL_31-8X6-35'              | 'Mech'    | 'EMPTY'  | 'DUMMY73'(!)          = ''       | ''        | 'DUMMY73'             |'SNLABEL_31-8X6-35'| 'SNLABEL_31-8X6-35'                               | ''      | ''            | ''           | ''        | 'MECHANICAL' | ''      | 'T6G-JOHN'     | ''                        | ''                                          | ''            | ''  | ''         | ''      | '20211013' | ''     | ''      | ''      | ''     | ''  | ''                  | ''                  
 'SNLABEL_10X6'                   | 'Mech'    | 'EMPTY'  | 'DUMMY74'(!)          = ''       | ''        | 'DUMMY74'             |'SNLABEL_10X6'| 'SNLABEL_10X6'                                    | ''      | ''            | ''           | ''        | 'MECHANICAL' | ''      | 'F0T-IVES'     | ''                        | ''                                          | ''            | ''  | ''         | ''      | '20220505' | ''     | ''      | ''      | ''     | ''  | ''                  | ''                  
 'G_PCB_VENDOR_LOGO_15X8'         | 'Mech'    | 'EMPTY'  | 'SP_DUMMY7'(!)        = ''       | ''        | 'DUMMY7'              |'G_PCB_VENDOR_LOGO_15X8'| 'G_PCB_VENDOR_LOGO_15X8 (FOR SEL)'                | ''      | ''            | ''           | ''        | 'MECHANICAL' | ''      | ''             | ''                        | ''                                          | ''            | ''  | ''         | ''      | '20221125' | ''     | ''      | ''      | ''     | ''  | ''                  | ''                  
 'SEL_UL_MARK_DATE_CODE_3X8-5'    | 'Mech'    | 'EMPTY'  | 'DUMMY75'(!)          = ''       | ''        | 'DUMMY75'             |'SEL_UL_MARK_DATE_CODE_3X8-5'| 'SEL_UL_MARK_DATE_CODE_3X8-5'                     | ''      | ''            | ''           | ''        | 'MECHANICAL' | ''      | 'S8G-BORAY'    | ''                        | 'SEL_UL_MARK_DATE_CODE_3X8-5.msg'           | ''            | ''  | ''         | ''      | '20230525' | ''     | ''      | ''      | ''     | ''  | ''                  | ''                  
 'SEL_2D_BARCODE_10X10'           | 'Mech'    | 'EMPTY'  | 'DUMMY76'(!)          = ''       | ''        | 'DUMMY76'             |'SEL_2D_BARCODE_10X10'| 'SEL_2D_BARCODE_10X10'                            | ''      | ''            | ''           | ''        | 'MECHANICAL' | ''      | 'S8G-BORAY'    | ''                        | 'SEL_2D_BARCODE_10X10.msg'                  | ''            | ''  | ''         | ''      | '20230525' | ''     | ''      | ''      | ''     | ''  | ''                  | ''                  

END_PART

END.

